# T6G (Grand Teton) — schematic netlist excerpt (pin names and nets, part order shuffled) for the footprints in the layout excerpt that follows; sources: Cadence DE-HDL packaged netlist, KiCad conversion of 04192023_DAF0TMB3IC0_F0TG_MB_C_brd_V02_OCP.brd

R1306  Q_RES  4.7K 1% EMPTY  pkg 0402LF  page 357 : A = GND ; B = INA230_6_A1
D93  Q_LED  IC  pkg SMLF  page 254 : A = LED_RST_RSMRST_PLD_R_N ; C = LED_RST_RSMRST_PLD_R_N_D

(kicad_pcb
	(version 20260206)
	(generator "pcbnew")
	(generator_version "10.0")
	(general
		(thickness 1.6)
		(legacy_teardrops no)
	)
	(paper "A4")
	(title_block
		(title "04192023_DAF0TMB3IC0_F0TG_MB_C_brd_V02_OCP.brd")
		(comment 1 "Grand Teton / footprints 3250-3251 of 8354")
	)
	(layers
		(0 "F.Cu" signal "TOP")
		(4 "In1.Cu" signal "GND")
		(6 "In2.Cu" signal "IN1")
		(8 "In3.Cu" signal "GND1")
		(10 "In4.Cu" signal "IN2")
		(12 "In5.Cu" signal "GND2")
		(14 "In6.Cu" signal "IN3")
		(16 "In7.Cu" signal "GND3")
		(18 "In8.Cu" signal "VCC")
		(20 "In9.Cu" signal "VCC1")
		(22 "In10.Cu" signal "GND4")
		(24 "In11.Cu" signal "IN4")
		(26 "In12.Cu" signal "GND5")
		(28 "In13.Cu" signal "IN5")
		(30 "In14.Cu" signal "GND6")
		(32 "In15.Cu" signal "IN6")
		(34 "In16.Cu" signal "GND7")
		(2 "B.Cu" signal "BOTTOM")
		(9 "F.Adhes" user "F.Adhesive")
		(11 "B.Adhes" user "B.Adhesive")
		(13 "F.Paste" user "Package Geometry/Pastemask Top")
		(15 "B.Paste" user "Package Geometry/Pastemask Bottom")
		(5 "F.SilkS" user "Ref Des/Silkscreen Top")
		(7 "B.SilkS" user "Ref Des/Silkscreen Bottom")
		(1 "F.Mask" user "Board Geometry/Soldermask Top")
		(3 "B.Mask" user "Board Geometry/Soldermask Bottom")
		(17 "Dwgs.User" user "User.Drawings")
		(19 "Cmts.User" user "User.Comments")
		(21 "Eco1.User" user "User.Eco1")
		(23 "Eco2.User" user "User.Eco2")
		(25 "Edge.Cuts" user "Board Geometry/Outline")
		(27 "Margin" user)
		(31 "F.CrtYd" user "Package Geometry/Place Bound Top")
		(29 "B.CrtYd" user "Package Geometry/Place Bound Bottom")
		(35 "F.Fab" user "Ref Des/Assembly Top")
		(33 "B.Fab" user "Ref Des/Assembly Bottom")
	)
	(footprint ""
		(layer "F.Cu")
		(at 310.411876 -70.098412 90)
		(property "Reference" "D93"
			(at -3.934714 -0.691642 90)
			(unlocked yes)
			(layer "F.SilkS")
			(effects
				(font
					(size 0.7874 0.5842)
					(thickness 0.1524)
				)
				(justify left)
			)
		)
		(property "Value" ""
			(at 0 0 90)
			(layer "F.Fab")
			(effects
				(font
					(size 1.27 1.27)
				)
			)
		)
		(duplicate_pad_numbers_are_jumpers no)
		(fp_line
			(start 1.16078 -0.4826)
			(end 1.16078 0.4826)
			(stroke
				(width 0.1524)
				(type default)
			)
			(layer "F.SilkS")
		)
		(fp_line
			(start 1.03378 -0.4826)
			(end 1.03378 0.4826)
			(stroke
				(width 0.1524)
				(type default)
			)
			(layer "F.SilkS")
		)
		(fp_line
			(start 0.90678 -0.4826)
			(end 0.90678 0.4826)
			(stroke
				(width 0.1524)
				(type default)
			)
			(layer "F.SilkS")
		)
		(fp_line
			(start -0.64008 -0.4826)
			(end 1.16078 -0.4826)
			(stroke
				(width 0.1524)
				(type default)
			)
			(layer "F.SilkS")
		)
		(fp_line
			(start -0.79248 -0.4826)
			(end 1.03378 -0.4826)
			(stroke
				(width 0.1524)
				(type default)
			)
			(layer "F.SilkS")
		)
		(fp_line
			(start -0.89408 -0.4826)
			(end 0.90678 -0.4826)
			(stroke
				(width 0.1524)
				(type default)
			)
			(layer "F.SilkS")
		)
		(fp_line
			(start 1.16078 0.4826)
			(end -0.64008 0.4826)
			(stroke
				(width 0.1524)
				(type default)
			)
			(layer "F.SilkS")
		)
		(fp_line
			(start 1.03378 0.4826)
			(end -0.79248 0.4826)
			(stroke
				(width 0.1524)
				(type default)
			)
			(layer "F.SilkS")
		)
		(fp_line
			(start 0.90678 0.4826)
			(end -0.90678 0.4826)
			(stroke
				(width 0.1524)
				(type default)
			)
			(layer "F.SilkS")
		)
		(fp_line
			(start -0.90678 0.4826)
			(end -0.90678 -0.4699)
			(stroke
				(width 0.1524)
				(type default)
			)
			(layer "F.SilkS")
		)
		(fp_line
			(start 0.499872 -0.249936)
			(end 0.499872 0.249936)
			(stroke
				(width 0.1)
				(type default)
			)
			(layer "F.Fab")
		)
		(fp_line
			(start -0.499872 -0.249936)
			(end 0.499872 -0.249936)
			(stroke
				(width 0.1)
				(type default)
			)
			(layer "F.Fab")
		)
		(fp_line
			(start 0.499872 0.249936)
			(end -0.499872 0.249936)
			(stroke
				(width 0.1)
				(type default)
			)
			(layer "F.Fab")
		)
		(fp_line
			(start -0.499872 0.249936)
			(end -0.499872 -0.249936)
			(stroke
				(width 0.1)
				(type default)
			)
			(layer "F.Fab")
		)
		(pad "A" smd rect
			(at -0.47498 0 90)
			(size 0.6096 0.7112)
			(layers "F.Cu" "F.Mask" "F.Paste")
			(net "LED_RST_RSMRST_PLD_R_N")
		)
		(pad "C" smd rect
			(at 0.47498 0 90)
			(size 0.6096 0.7112)
			(layers "F.Cu" "F.Mask" "F.Paste")
			(net "LED_RST_RSMRST_PLD_R_N_D")
		)
	)
	(footprint ""
		(layer "F.Cu")
		(at 391.291318 -77.423264)
		(property "Reference" "R1306"
			(at 0 0 0)
			(layer "F.SilkS")
			(hide yes)
			(effects
				(font
					(size 1.27 1.27)
				)
			)
		)
		(property "Value" ""
			(at 0 0 0)
			(layer "F.Fab")
			(effects
				(font
					(size 1.27 1.27)
				)
			)
		)
		(duplicate_pad_numbers_are_jumpers no)
		(fp_line
			(start -0.7874 -0.4064)
			(end 0.7874 -0.4064)
			(stroke
				(width 0.1524)
				(type default)
			)
			(layer "F.SilkS")
		)
		(fp_line
			(start -0.7874 0.4064)
			(end -0.7874 -0.4064)
			(stroke
				(width 0.1524)
				(type default)
			)
			(layer "F.SilkS")
		)
		(fp_line
			(start 0.7874 -0.4064)
			(end 0.7874 0.4064)
			(stroke
				(width 0.1524)
				(type default)
			)
			(layer "F.SilkS")
		)
		(fp_line
			(start 0.7874 0.4064)
			(end -0.7874 0.4064)
			(stroke
				(width 0.1524)
				(type default)
			)
			(layer "F.SilkS")
		)
		(fp_line
			(start -0.67945 -0.305054)
			(end -0.12065 -0.305054)
			(stroke
				(width 0.1)
				(type default)
			)
			(layer "F.Fab")
		)
		(fp_line
			(start -0.67945 0.3048)
			(end -0.67945 -0.305054)
			(stroke
				(width 0.1)
				(type default)
			)
			(layer "F.Fab")
		)
		(fp_line
			(start -0.12065 -0.305054)
			(end -0.12065 -0.2794)
			(stroke
				(width 0.1)
				(type default)
			)
			(layer "F.Fab")
		)
		(fp_line
			(start -0.12065 -0.2794)
			(end 0.12065 -0.2794)
			(stroke
				(width 0.1)
				(type default)
			)
			(layer "F.Fab")
		)
		(fp_line
			(start -0.12065 0.2794)
			(end -0.12065 0.3048)
			(stroke
				(width 0.1)
				(type default)
			)
			(layer "F.Fab")
		)
		(fp_line
			(start -0.12065 0.3048)
			(end -0.67945 0.3048)
			(stroke
				(width 0.1)
				(type default)
			)
			(layer "F.Fab")
		)
		(fp_line
			(start 0.120396 0.2794)
			(end -0.12065 0.2794)
			(stroke
				(width 0.1)
				(type default)
			)
			(layer "F.Fab")
		)
		(fp_line
			(start 0.120396 0.3048)
			(end 0.120396 0.2794)
			(stroke
				(width 0.1)
				(type default)
			)
			(layer "F.Fab")
		)
		(fp_line
			(start 0.12065 -0.3048)
			(end 0.67945 -0.3048)
			(stroke
				(width 0.1)
				(type default)
			)
			(layer "F.Fab")
		)
		(fp_line
			(start 0.12065 -0.2794)
			(end 0.12065 -0.3048)
			(stroke
				(width 0.1)
				(type default)
			)
			(layer "F.Fab")
		)
		(fp_line
			(start 0.67945 -0.3048)
			(end 0.67945 0.3048)
			(stroke
				(width 0.1)
				(type default)
			)
			(layer "F.Fab")
		)
		(fp_line
			(start 0.67945 0.3048)
			(end 0.120396 0.3048)
			(stroke
				(width 0.1)
				(type default)
			)
			(layer "F.Fab")
		)
		(pad "1" smd circle
			(at -0.40005 0)
			(size 0 0)
			(layers "F.Cu" "F.Mask" "F.Paste")
			(net "GND")
		)
		(pad "2" smd circle
			(at 0.40005 0)
			(size 0 0)
			(layers "F.Cu" "F.Mask" "F.Paste")
			(net "INA230_6_A1")
		)
	)
)
